(kicad_pcb
	(version 20241229)
	(generator "pcbnew")
	(generator_version "9.0")
	(general
		(thickness 1.62)
		(legacy_teardrops no)
	)
	(paper "A3")
	(title_block
		(title "COM Express 7 Baseboard")
		(date "2025-02-04")
		(rev "1.1.2")
		(company "Antmicro Ltd")
		(comment 1 "www.antmicro.com")
		(comment 9 "footprints 713-715 of 802")
	)
	(layers
		(0 "F.Cu" signal)
		(4 "In1.Cu" signal)
		(6 "In2.Cu" signal)
		(8 "In3.Cu" signal)
		(10 "In4.Cu" signal)
		(12 "In5.Cu" signal)
		(14 "In6.Cu" signal)
		(2 "B.Cu" signal)
		(9 "F.Adhes" user "F.Adhesive")
		(11 "B.Adhes" user "B.Adhesive")
		(13 "F.Paste" user)
		(15 "B.Paste" user)
		(5 "F.SilkS" user "F.Silkscreen")
		(7 "B.SilkS" user "B.Silkscreen")
		(1 "F.Mask" user)
		(3 "B.Mask" user)
		(17 "Dwgs.User" user "User.Drawings")
		(19 "Cmts.User" user "User.Comments")
		(21 "Eco1.User" user "User.Eco1")
		(23 "Eco2.User" user "User.Eco2")
		(25 "Edge.Cuts" user)
		(27 "Margin" user)
		(31 "F.CrtYd" user "F.Courtyard")
		(29 "B.CrtYd" user "B.Courtyard")
		(35 "F.Fab" user)
		(33 "B.Fab" user)
	)
	(footprint "antmicro-footprints:R_0402_1005Metric"
		(layer "B.Cu")
		(at 121.7 163.56 180)
		(descr "Resistor SMD 0402")
		(tags "resistor SMD 0402")
		(property "Reference" "R76"
			(at -1.1 -1.4 0)
			(layer "B.SilkS")
			(effects
				(font
					(size 0.7 0.7)
					(thickness 0.15)
				)
				(justify left bottom mirror)
			)
		)
		(property "Value" "R_0R_0402"
			(at -1.011843 -1.772047 0)
			(layer "B.Fab")
			(effects
				(font
					(size 0.7 0.7)
					(thickness 0.15)
				)
				(justify left bottom mirror)
			)
		)
		(property "Datasheet" "https://industrial.panasonic.com/cdbs/www-data/pdf/RDA0000/AOA0000C301.pdf"
			(at 0 0 180)
			(layer "F.Fab")
			(hide yes)
			(effects
				(font
					(size 1.27 1.27)
					(thickness 0.15)
				)
			)
		)
		(property "Author" "Antmicro"
			(at 243.4 327.12 0)
			(layer "B.Fab")
			(hide yes)
			(effects
				(font
					(size 1 1)
					(thickness 0.15)
				)
				(justify mirror)
			)
		)
		(property "Current" "1A"
			(at 243.4 327.12 0)
			(layer "B.Fab")
			(hide yes)
			(effects
				(font
					(size 1 1)
					(thickness 0.15)
				)
				(justify mirror)
			)
		)
		(property "License" "Apache-2.0"
			(at 243.4 327.12 0)
			(layer "B.Fab")
			(hide yes)
			(effects
				(font
					(size 1 1)
					(thickness 0.15)
				)
				(justify mirror)
			)
		)
		(property "MPN" "ERJ2GE0R00X"
			(at 243.4 327.12 0)
			(layer "B.Fab")
			(hide yes)
			(effects
				(font
					(size 1 1)
					(thickness 0.15)
				)
				(justify mirror)
			)
		)
		(property "Manufacturer" "Panasonic"
			(at 243.4 327.12 0)
			(layer "B.Fab")
			(hide yes)
			(effects
				(font
					(size 1 1)
					(thickness 0.15)
				)
				(justify mirror)
			)
		)
		(property "Public" "False"
			(at 243.4 327.12 0)
			(layer "B.Fab")
			(hide yes)
			(effects
				(font
					(size 1 1)
					(thickness 0.15)
				)
				(justify mirror)
			)
		)
		(property "Tolerance" ""
			(at 243.4 327.12 0)
			(layer "B.Fab")
			(hide yes)
			(effects
				(font
					(size 1 1)
					(thickness 0.15)
				)
				(justify mirror)
			)
		)
		(property "Val" "0R"
			(at 243.4 327.12 0)
			(layer "B.Fab")
			(hide yes)
			(effects
				(font
					(size 1 1)
					(thickness 0.15)
				)
				(justify mirror)
			)
		)
		(sheetname "OCuLink")
		(sheetfile "oculink.kicad_sch")
		(attr smd)
		(fp_rect
			(start -0.925 0.47)
			(end 0.925 -0.47)
			(stroke
				(width 0.05)
				(type default)
			)
			(fill no)
			(layer "B.CrtYd")
		)
		(fp_rect
			(start -0.5 0.25)
			(end 0.5 -0.25)
			(stroke
				(width 0.15)
				(type solid)
			)
			(fill no)
			(layer "B.Fab")
		)
		(pad "1" smd roundrect
			(at -0.48 0 180)
			(size 0.59 0.64)
			(layers "B.Cu" "B.Mask" "B.Paste")
			(roundrect_rratio 0.25)
			(net 528 "/Backplane/~{PERST}")
			(pintype "passive")
			(teardrops
				(best_length_ratio 0.2)
				(max_length 1)
				(best_width_ratio 0.9)
				(max_width 2)
				(curved_edges yes)
				(filter_ratio 0.9)
				(enabled yes)
				(allow_two_segments yes)
				(prefer_zone_connections yes)
			)
		)
		(pad "2" smd roundrect
			(at 0.48 0 180)
			(size 0.59 0.64)
			(layers "B.Cu" "B.Mask" "B.Paste")
			(roundrect_rratio 0.25)
			(net 200 "/OCuLink/~{PERST_D0}")
			(pintype "passive")
			(teardrops
				(best_length_ratio 0.2)
				(max_length 1)
				(best_width_ratio 0.9)
				(max_width 2)
				(curved_edges yes)
				(filter_ratio 0.9)
				(enabled yes)
				(allow_two_segments yes)
				(prefer_zone_connections yes)
			)
		)
	)
	(footprint "antmicro-footprints:USON-10_2.5x1mm_P0.5mm"
		(layer "B.Cu")
		(at 104.77 165.61)
		(descr "USON-10 2.5x1mm_ Pitch 0.5mm")
		(tags "USON-10 2.5x1mm Pitch 0.5mm")
		(property "Reference" "U10"
			(at 1.72 1.05 90)
			(layer "B.SilkS")
			(effects
				(font
					(size 0.7 0.7)
					(thickness 0.15)
				)
				(justify right bottom mirror)
			)
		)
		(property "Value" "ESD204DQAR"
			(at 0.018 -2.499 0)
			(layer "B.Fab")
			(effects
				(font
					(size 0.7 0.7)
					(thickness 0.15)
				)
				(justify right bottom mirror)
			)
		)
		(property "Datasheet" "https://www.ti.com/lit/ds/symlink/esd204.pdf?ts=1706004844383&ref_url=https%253A%252F%252Fwww.ti.com%252Finterface%252Fdiodes%252Fesd-protection-diodes%252Fproducts.html"
			(at 0 0 0)
			(layer "F.Fab")
			(hide yes)
			(effects
				(font
					(size 1.27 1.27)
					(thickness 0.15)
				)
			)
		)
		(property "Author" "Antmicro"
			(at 0 0 0)
			(layer "B.Fab")
			(hide yes)
			(effects
				(font
					(size 1 1)
					(thickness 0.15)
				)
				(justify mirror)
			)
		)
		(property "License" "Apache-2.0"
			(at 0 0 0)
			(layer "B.Fab")
			(hide yes)
			(effects
				(font
					(size 1 1)
					(thickness 0.15)
				)
				(justify mirror)
			)
		)
		(property "MPN" "ESD204DQAR"
			(at 0 0 0)
			(layer "B.Fab")
			(hide yes)
			(effects
				(font
					(size 1 1)
					(thickness 0.15)
				)
				(justify mirror)
			)
		)
		(property "Manufacturer" "Texas Instruments"
			(at 0 0 0)
			(layer "B.Fab")
			(hide yes)
			(effects
				(font
					(size 1 1)
					(thickness 0.15)
				)
				(justify mirror)
			)
		)
		(sheetname "OCuLink")
		(sheetfile "oculink.kicad_sch")
		(attr smd)
		(fp_line
			(start -0.5 -1.398)
			(end 0.498 -1.398)
			(stroke
				(width 0.15)
				(type solid)
			)
			(layer "B.SilkS")
		)
		(fp_line
			(start -0.5 1.401)
			(end 0.498 1.401)
			(stroke
				(width 0.15)
				(type solid)
			)
			(layer "B.SilkS")
		)
		(fp_circle
			(center -0.68 1.27)
			(end -0.63 1.27)
			(stroke
				(width 0.15)
				(type solid)
			)
			(fill yes)
			(layer "B.SilkS")
		)
		(fp_rect
			(start -0.8 1.5)
			(end 0.8 -1.499)
			(stroke
				(width 0.05)
				(type solid)
			)
			(fill no)
			(layer "B.CrtYd")
		)
		(fp_line
			(start -0.5 -1.249)
			(end -0.5 1)
			(stroke
				(width 0.15)
				(type solid)
			)
			(layer "B.Fab")
		)
		(fp_line
			(start -0.5 1)
			(end -0.25 1.25)
			(stroke
				(width 0.15)
				(type solid)
			)
			(layer "B.Fab")
		)
		(fp_line
			(start -0.25 1.25)
			(end 0.498 1.25)
			(stroke
				(width 0.15)
				(type solid)
			)
			(layer "B.Fab")
		)
		(fp_line
			(start 0.498 -1.249)
			(end -0.5 -1.249)
			(stroke
				(width 0.15)
				(type solid)
			)
			(layer "B.Fab")
		)
		(fp_line
			(start 0.498 -1.249)
			(end 0.498 1.25)
			(stroke
				(width 0.15)
				(type solid)
			)
			(layer "B.Fab")
		)
		(pad "1" smd roundrect
			(at -0.387 1 90)
			(size 0.25 0.55)
			(layers "B.Cu" "B.Mask" "B.Paste")
			(roundrect_rratio 0.25)
			(net 100 "/OCuLink/PCIe_{x4}.TX0+")
			(pintype "passive")
			(teardrops
				(best_length_ratio 0.2)
				(max_length 1)
				(best_width_ratio 0.9)
				(max_width 2)
				(curved_edges yes)
				(filter_ratio 0.9)
				(enabled yes)
				(allow_two_segments yes)
				(prefer_zone_connections yes)
			)
		)
		(pad "2" smd roundrect
			(at -0.387 0.5 90)
			(size 0.25 0.55)
			(layers "B.Cu" "B.Mask" "B.Paste")
			(roundrect_rratio 0.25)
			(net 95 "/OCuLink/PCIe_{x4}.TX0-")
			(pintype "passive")
			(teardrops
				(best_length_ratio 0.2)
				(max_length 1)
				(best_width_ratio 0.9)
				(max_width 2)
				(curved_edges yes)
				(filter_ratio 0.9)
				(enabled yes)
				(allow_two_segments yes)
				(prefer_zone_connections yes)
			)
		)
		(pad "3" smd roundrect
			(at -0.387 0 90)
			(size 0.4 0.55)
			(layers "B.Cu" "B.Mask" "B.Paste")
			(roundrect_rratio 0.25)
			(net 1 "GND")
			(pintype "power_in")
			(teardrops
				(best_length_ratio 0.2)
				(max_length 1)
				(best_width_ratio 0.9)
				(max_width 2)
				(curved_edges yes)
				(filter_ratio 0.9)
				(enabled yes)
				(allow_two_segments yes)
				(prefer_zone_connections yes)
			)
		)
		(pad "4" smd roundrect
			(at -0.387 -0.498 90)
			(size 0.25 0.55)
			(layers "B.Cu" "B.Mask" "B.Paste")
			(roundrect_rratio 0.25)
			(net 102 "/OCuLink/PCIe_{x4}.TX1+")
			(pintype "passive")
			(teardrops
				(best_length_ratio 0.2)
				(max_length 1)
				(best_width_ratio 0.9)
				(max_width 2)
				(curved_edges yes)
				(filter_ratio 0.9)
				(enabled yes)
				(allow_two_segments yes)
				(prefer_zone_connections yes)
			)
		)
		(pad "5" smd roundrect
			(at -0.387 -0.998 90)
			(size 0.25 0.55)
			(layers "B.Cu" "B.Mask" "B.Paste")
			(roundrect_rratio 0.25)
			(net 96 "/OCuLink/PCIe_{x4}.TX1-")
			(pintype "passive")
			(teardrops
				(best_length_ratio 0.2)
				(max_length 1)
				(best_width_ratio 0.9)
				(max_width 2)
				(curved_edges yes)
				(filter_ratio 0.9)
				(enabled yes)
				(allow_two_segments yes)
				(prefer_zone_connections yes)
			)
		)
		(pad "6" smd roundrect
			(at 0.385 -0.998 90)
			(size 0.25 0.55)
			(layers "B.Cu" "B.Mask" "B.Paste")
			(roundrect_rratio 0.25)
			(net 96 "/OCuLink/PCIe_{x4}.TX1-")
			(pintype "passive")
			(teardrops
				(best_length_ratio 0.2)
				(max_length 1)
				(best_width_ratio 0.9)
				(max_width 2)
				(curved_edges yes)
				(filter_ratio 0.9)
				(enabled yes)
				(allow_two_segments yes)
				(prefer_zone_connections yes)
			)
		)
		(pad "7" smd roundrect
			(at 0.385 -0.498 90)
			(size 0.25 0.55)
			(layers "B.Cu" "B.Mask" "B.Paste")
			(roundrect_rratio 0.25)
			(net 102 "/OCuLink/PCIe_{x4}.TX1+")
			(pintype "passive")
			(teardrops
				(best_length_ratio 0.2)
				(max_length 1)
				(best_width_ratio 0.9)
				(max_width 2)
				(curved_edges yes)
				(filter_ratio 0.9)
				(enabled yes)
				(allow_two_segments yes)
				(prefer_zone_connections yes)
			)
		)
		(pad "8" smd roundrect
			(at 0.385 0 90)
			(size 0.4 0.55)
			(layers "B.Cu" "B.Mask" "B.Paste")
			(roundrect_rratio 0.25)
			(net 1 "GND")
			(pintype "passive")
			(teardrops
				(best_length_ratio 0.2)
				(max_length 1)
				(best_width_ratio 0.9)
				(max_width 2)
				(curved_edges yes)
				(filter_ratio 0.9)
				(enabled yes)
				(allow_two_segments yes)
				(prefer_zone_connections yes)
			)
		)
		(pad "9" smd roundrect
			(at 0.385 0.5 90)
			(size 0.25 0.55)
			(layers "B.Cu" "B.Mask" "B.Paste")
			(roundrect_rratio 0.25)
			(net 95 "/OCuLink/PCIe_{x4}.TX0-")
			(pintype "passive")
			(teardrops
				(best_length_ratio 0.2)
				(max_length 1)
				(best_width_ratio 0.9)
				(max_width 2)
				(curved_edges yes)
				(filter_ratio 0.9)
				(enabled yes)
				(allow_two_segments yes)
				(prefer_zone_connections yes)
			)
		)
		(pad "10" smd roundrect
			(at 0.385 1 90)
			(size 0.25 0.55)
			(layers "B.Cu" "B.Mask" "B.Paste")
			(roundrect_rratio 0.25)
			(net 100 "/OCuLink/PCIe_{x4}.TX0+")
			(pintype "passive")
			(teardrops
				(best_length_ratio 0.2)
				(max_length 1)
				(best_width_ratio 0.9)
				(max_width 2)
				(curved_edges yes)
				(filter_ratio 0.9)
				(enabled yes)
				(allow_two_segments yes)
				(prefer_zone_connections yes)
			)
		)
	)
	(footprint "antmicro-footprints:R_0402_1005Metric"
		(layer "B.Cu")
		(at 112.4 69.86 -90)
		(descr "Resistor SMD 0402")
		(tags "resistor SMD 0402")
		(property "Reference" "R72"
			(at 0.8 -0.45 90)
			(layer "B.SilkS")
			(effects
				(font
					(size 0.7 0.7)
					(thickness 0.15)
				)
				(justify left bottom mirror)
			)
		)
		(property "Value" "R_220R_0402"
			(at -1.011843 -1.772047 90)
			(layer "B.Fab")
			(effects
				(font
					(size 0.7 0.7)
					(thickness 0.15)
				)
				(justify left bottom mirror)
			)
		)
		(property "Datasheet" "https://www.bourns.com/docs/product-datasheets/cr.pdf"
			(at 0 0 270)
			(layer "F.Fab")
			(hide yes)
			(effects
				(font
					(size 1.27 1.27)
					(thickness 0.15)
				)
			)
		)
		(property "Author" "Antmicro"
			(at 42.54 182.26 0)
			(layer "B.Fab")
			(hide yes)
			(effects
				(font
					(size 1 1)
					(thickness 0.15)
				)
				(justify mirror)
			)
		)
		(property "License" "Apache-2.0"
			(at 42.54 182.26 0)
			(layer "B.Fab")
			(hide yes)
			(effects
				(font
					(size 1 1)
					(thickness 0.15)
				)
				(justify mirror)
			)
		)
		(property "MPN" "CR0402-FX-2200GLF"
			(at 42.54 182.26 0)
			(layer "B.Fab")
			(hide yes)
			(effects
				(font
					(size 1 1)
					(thickness 0.15)
				)
				(justify mirror)
			)
		)
		(property "Manufacturer" "Bourns"
			(at 42.54 182.26 0)
			(layer "B.Fab")
			(hide yes)
			(effects
				(font
					(size 1 1)
					(thickness 0.15)
				)
				(justify mirror)
			)
		)
		(property "Public" "False"
			(at 42.54 182.26 0)
			(layer "B.Fab")
			(hide yes)
			(effects
				(font
					(size 1 1)
					(thickness 0.15)
				)
				(justify mirror)
			)
		)
		(property "Tolerance" "1%"
			(at 42.54 182.26 0)
			(layer "B.Fab")
			(hide yes)
			(effects
				(font
					(size 1 1)
					(thickness 0.15)
				)
				(justify mirror)
			)
		)
		(property "Val" "220R"
			(at 42.54 182.26 0)
			(layer "B.Fab")
			(hide yes)
			(effects
				(font
					(size 1 1)
					(thickness 0.15)
				)
				(justify mirror)
			)
		)
		(sheetname "USB-C console")
		(sheetfile "usb-c_console.kicad_sch")
		(attr smd)
		(fp_rect
			(start -0.925 0.47)
			(end 0.925 -0.47)
			(stroke
				(width 0.05)
				(type default)
			)
			(fill no)
			(layer "B.CrtYd")
		)
		(fp_rect
			(start -0.5 0.25)
			(end 0.5 -0.25)
			(stroke
				(width 0.15)
				(type solid)
			)
			(fill no)
			(layer "B.Fab")
		)
		(pad "1" smd roundrect
			(at -0.48 0 270)
			(size 0.59 0.64)
			(layers "B.Cu" "B.Mask" "B.Paste")
			(roundrect_rratio 0.25)
			(net 933 "Net-(D11-A)")
			(pintype "passive")
			(teardrops
				(best_length_ratio 0.2)
				(max_length 1)
				(best_width_ratio 0.9)
				(max_width 2)
				(curved_edges yes)
				(filter_ratio 0.9)
				(enabled yes)
				(allow_two_segments yes)
				(prefer_zone_connections yes)
			)
		)
		(pad "2" smd roundrect
			(at 0.48 0 270)
			(size 0.59 0.64)
			(layers "B.Cu" "B.Mask" "B.Paste")
			(roundrect_rratio 0.25)
			(net 57 "/USB-C console/FTDI_VCCIO")
			(pintype "passive")
			(teardrops
				(best_length_ratio 0.2)
				(max_length 1)
				(best_width_ratio 0.9)
				(max_width 2)
				(curved_edges yes)
				(filter_ratio 0.9)
				(enabled yes)
				(allow_two_segments yes)
				(prefer_zone_connections yes)
			)
		)
	)
)
